(kicad_pcb
	(version 20260206)
	(generator "pcbnew")
	(generator_version "10.0")
	(general
		(thickness 1.6)
		(legacy_teardrops no)
	)
	(paper "A4")
	(title_block
		(title "03242023_DA0F0TMBIJ0_F0T_Motherboard_J_brd_V01_OCP.brd")
		(comment 1 "Grand Teton / footprints 722-728 of 6105")
	)
	(layers
		(0 "F.Cu" signal "TOP")
		(4 "In1.Cu" signal "GND")
		(6 "In2.Cu" signal "IN1")
		(8 "In3.Cu" signal "GND1")
		(10 "In4.Cu" signal "IN2")
		(12 "In5.Cu" signal "GND2")
		(14 "In6.Cu" signal "IN3")
		(16 "In7.Cu" signal "GND3")
		(18 "In8.Cu" signal "VCC")
		(20 "In9.Cu" signal "VCC1")
		(22 "In10.Cu" signal "GND4")
		(24 "In11.Cu" signal "IN4")
		(26 "In12.Cu" signal "GND5")
		(28 "In13.Cu" signal "IN5")
		(30 "In14.Cu" signal "GND6")
		(32 "In15.Cu" signal "IN6")
		(34 "In16.Cu" signal "GND7")
		(2 "B.Cu" signal "BOTTOM")
		(9 "F.Adhes" user "F.Adhesive")
		(11 "B.Adhes" user "B.Adhesive")
		(13 "F.Paste" user "Package Geometry/Pastemask Top")
		(15 "B.Paste" user "Package Geometry/Pastemask Bottom")
		(5 "F.SilkS" user "Ref Des/Silkscreen Top")
		(7 "B.SilkS" user "Ref Des/Silkscreen Bottom")
		(1 "F.Mask" user "Board Geometry/Soldermask Top")
		(3 "B.Mask" user "Board Geometry/Soldermask Bottom")
		(17 "Dwgs.User" user "User.Drawings")
		(19 "Cmts.User" user "User.Comments")
		(21 "Eco1.User" user "User.Eco1")
		(23 "Eco2.User" user "User.Eco2")
		(25 "Edge.Cuts" user "Board Geometry/Outline")
		(27 "Margin" user)
		(31 "F.CrtYd" user "Package Geometry/Place Bound Top")
		(29 "B.CrtYd" user "Package Geometry/Place Bound Bottom")
		(35 "F.Fab" user "Ref Des/Assembly Top")
		(33 "B.Fab" user "Ref Des/Assembly Bottom")
	)
	(footprint ""
		(layer "F.Cu")
		(at 54.242716 -109.91469 180)
		(property "Reference" "R3718"
			(at 0 0 180)
			(layer "F.SilkS")
			(hide yes)
			(effects
				(font
					(size 1.27 1.27)
				)
			)
		)
		(property "Value" ""
			(at 0 0 180)
			(layer "F.Fab")
			(effects
				(font
					(size 1.27 1.27)
				)
			)
		)
		(duplicate_pad_numbers_are_jumpers no)
		(fp_line
			(start 0.7874 0.4064)
			(end -0.7874 0.4064)
			(stroke
				(width 0.1524)
				(type default)
			)
			(layer "F.SilkS")
		)
		(fp_line
			(start 0.7874 -0.4064)
			(end 0.7874 0.4064)
			(stroke
				(width 0.1524)
				(type default)
			)
			(layer "F.SilkS")
		)
		(fp_line
			(start -0.7874 0.4064)
			(end -0.7874 -0.4064)
			(stroke
				(width 0.1524)
				(type default)
			)
			(layer "F.SilkS")
		)
		(fp_line
			(start -0.7874 -0.4064)
			(end 0.7874 -0.4064)
			(stroke
				(width 0.1524)
				(type default)
			)
			(layer "F.SilkS")
		)
		(fp_line
			(start 0.67945 0.3048)
			(end 0.120396 0.3048)
			(stroke
				(width 0.1)
				(type default)
			)
			(layer "F.Fab")
		)
		(fp_line
			(start 0.67945 -0.3048)
			(end 0.67945 0.3048)
			(stroke
				(width 0.1)
				(type default)
			)
			(layer "F.Fab")
		)
		(fp_line
			(start 0.12065 -0.2794)
			(end 0.12065 -0.3048)
			(stroke
				(width 0.1)
				(type default)
			)
			(layer "F.Fab")
		)
		(fp_line
			(start 0.12065 -0.3048)
			(end 0.67945 -0.3048)
			(stroke
				(width 0.1)
				(type default)
			)
			(layer "F.Fab")
		)
		(fp_line
			(start 0.120396 0.3048)
			(end 0.120396 0.2794)
			(stroke
				(width 0.1)
				(type default)
			)
			(layer "F.Fab")
		)
		(fp_line
			(start 0.120396 0.2794)
			(end -0.12065 0.2794)
			(stroke
				(width 0.1)
				(type default)
			)
			(layer "F.Fab")
		)
		(fp_line
			(start -0.12065 0.3048)
			(end -0.67945 0.3048)
			(stroke
				(width 0.1)
				(type default)
			)
			(layer "F.Fab")
		)
		(fp_line
			(start -0.12065 0.2794)
			(end -0.12065 0.3048)
			(stroke
				(width 0.1)
				(type default)
			)
			(layer "F.Fab")
		)
		(fp_line
			(start -0.12065 -0.2794)
			(end 0.12065 -0.2794)
			(stroke
				(width 0.1)
				(type default)
			)
			(layer "F.Fab")
		)
		(fp_line
			(start -0.12065 -0.305054)
			(end -0.12065 -0.2794)
			(stroke
				(width 0.1)
				(type default)
			)
			(layer "F.Fab")
		)
		(fp_line
			(start -0.67945 0.3048)
			(end -0.67945 -0.305054)
			(stroke
				(width 0.1)
				(type default)
			)
			(layer "F.Fab")
		)
		(fp_line
			(start -0.67945 -0.305054)
			(end -0.12065 -0.305054)
			(stroke
				(width 0.1)
				(type default)
			)
			(layer "F.Fab")
		)
		(pad "1" smd circle
			(at -0.40005 0 180)
			(size 0 0)
			(layers "F.Cu" "F.Mask" "F.Paste")
			(net "SMB_LM75_1_3V3AUX_SDA_R")
		)
		(pad "2" smd circle
			(at 0.40005 0 180)
			(size 0 0)
			(layers "F.Cu" "F.Mask" "F.Paste")
			(net "SMB_LM75_1_3V3AUX_SDA")
		)
	)
	(footprint ""
		(layer "F.Cu")
		(at 51.593496 -118.93677)
		(property "Reference" "R3708"
			(at 0 0 0)
			(layer "F.SilkS")
			(hide yes)
			(effects
				(font
					(size 1.27 1.27)
				)
			)
		)
		(property "Value" ""
			(at 0 0 0)
			(layer "F.Fab")
			(effects
				(font
					(size 1.27 1.27)
				)
			)
		)
		(duplicate_pad_numbers_are_jumpers no)
		(fp_line
			(start -0.7874 -0.4064)
			(end 0.7874 -0.4064)
			(stroke
				(width 0.1524)
				(type default)
			)
			(layer "F.SilkS")
		)
		(fp_line
			(start -0.7874 0.4064)
			(end -0.7874 -0.4064)
			(stroke
				(width 0.1524)
				(type default)
			)
			(layer "F.SilkS")
		)
		(fp_line
			(start 0.7874 -0.4064)
			(end 0.7874 0.4064)
			(stroke
				(width 0.1524)
				(type default)
			)
			(layer "F.SilkS")
		)
		(fp_line
			(start 0.7874 0.4064)
			(end -0.7874 0.4064)
			(stroke
				(width 0.1524)
				(type default)
			)
			(layer "F.SilkS")
		)
		(fp_line
			(start -0.67945 -0.305054)
			(end -0.12065 -0.305054)
			(stroke
				(width 0.1)
				(type default)
			)
			(layer "F.Fab")
		)
		(fp_line
			(start -0.67945 0.3048)
			(end -0.67945 -0.305054)
			(stroke
				(width 0.1)
				(type default)
			)
			(layer "F.Fab")
		)
		(fp_line
			(start -0.12065 -0.305054)
			(end -0.12065 -0.2794)
			(stroke
				(width 0.1)
				(type default)
			)
			(layer "F.Fab")
		)
		(fp_line
			(start -0.12065 -0.2794)
			(end 0.12065 -0.2794)
			(stroke
				(width 0.1)
				(type default)
			)
			(layer "F.Fab")
		)
		(fp_line
			(start -0.12065 0.2794)
			(end -0.12065 0.3048)
			(stroke
				(width 0.1)
				(type default)
			)
			(layer "F.Fab")
		)
		(fp_line
			(start -0.12065 0.3048)
			(end -0.67945 0.3048)
			(stroke
				(width 0.1)
				(type default)
			)
			(layer "F.Fab")
		)
		(fp_line
			(start 0.120396 0.2794)
			(end -0.12065 0.2794)
			(stroke
				(width 0.1)
				(type default)
			)
			(layer "F.Fab")
		)
		(fp_line
			(start 0.120396 0.3048)
			(end 0.120396 0.2794)
			(stroke
				(width 0.1)
				(type default)
			)
			(layer "F.Fab")
		)
		(fp_line
			(start 0.12065 -0.3048)
			(end 0.67945 -0.3048)
			(stroke
				(width 0.1)
				(type default)
			)
			(layer "F.Fab")
		)
		(fp_line
			(start 0.12065 -0.2794)
			(end 0.12065 -0.3048)
			(stroke
				(width 0.1)
				(type default)
			)
			(layer "F.Fab")
		)
		(fp_line
			(start 0.67945 -0.3048)
			(end 0.67945 0.3048)
			(stroke
				(width 0.1)
				(type default)
			)
			(layer "F.Fab")
		)
		(fp_line
			(start 0.67945 0.3048)
			(end 0.120396 0.3048)
			(stroke
				(width 0.1)
				(type default)
			)
			(layer "F.Fab")
		)
		(pad "1" smd circle
			(at -0.40005 0)
			(size 0 0)
			(layers "F.Cu" "F.Mask" "F.Paste")
			(net "P3V3_AUX")
		)
		(pad "2" smd circle
			(at 0.40005 0)
			(size 0 0)
			(layers "F.Cu" "F.Mask" "F.Paste")
			(net "PCA9548_PCIE0_ADDR0")
		)
	)
	(footprint ""
		(layer "F.Cu")
		(at 362.65358 -363.5121)
		(property "Reference" "PC2361"
			(at 0 0 0)
			(layer "F.SilkS")
			(hide yes)
			(effects
				(font
					(size 1.27 1.27)
				)
			)
		)
		(property "Value" ""
			(at 0 0 0)
			(layer "F.Fab")
			(effects
				(font
					(size 1.27 1.27)
				)
			)
		)
		(duplicate_pad_numbers_are_jumpers no)
		(fp_line
			(start -0.7874 -0.4064)
			(end 0.7874 -0.4064)
			(stroke
				(width 0.1524)
				(type default)
			)
			(layer "F.SilkS")
		)
		(fp_line
			(start -0.7874 0.4064)
			(end -0.7874 -0.4064)
			(stroke
				(width 0.1524)
				(type default)
			)
			(layer "F.SilkS")
		)
		(fp_line
			(start 0.7874 -0.4064)
			(end 0.7874 0.4064)
			(stroke
				(width 0.1524)
				(type default)
			)
			(layer "F.SilkS")
		)
		(fp_line
			(start 0.7874 0.4064)
			(end -0.7874 0.4064)
			(stroke
				(width 0.1524)
				(type default)
			)
			(layer "F.SilkS")
		)
		(fp_line
			(start -0.67945 -0.305054)
			(end -0.12065 -0.305054)
			(stroke
				(width 0.1)
				(type default)
			)
			(layer "F.Fab")
		)
		(fp_line
			(start -0.67945 0.3048)
			(end -0.67945 -0.305054)
			(stroke
				(width 0.1)
				(type default)
			)
			(layer "F.Fab")
		)
		(fp_line
			(start -0.12065 -0.305054)
			(end -0.12065 -0.2794)
			(stroke
				(width 0.1)
				(type default)
			)
			(layer "F.Fab")
		)
		(fp_line
			(start -0.12065 -0.2794)
			(end 0.12065 -0.2794)
			(stroke
				(width 0.1)
				(type default)
			)
			(layer "F.Fab")
		)
		(fp_line
			(start -0.12065 0.2794)
			(end -0.12065 0.3048)
			(stroke
				(width 0.1)
				(type default)
			)
			(layer "F.Fab")
		)
		(fp_line
			(start -0.12065 0.3048)
			(end -0.67945 0.3048)
			(stroke
				(width 0.1)
				(type default)
			)
			(layer "F.Fab")
		)
		(fp_line
			(start 0.120396 0.2794)
			(end -0.12065 0.2794)
			(stroke
				(width 0.1)
				(type default)
			)
			(layer "F.Fab")
		)
		(fp_line
			(start 0.120396 0.3048)
			(end 0.120396 0.2794)
			(stroke
				(width 0.1)
				(type default)
			)
			(layer "F.Fab")
		)
		(fp_line
			(start 0.12065 -0.3048)
			(end 0.67945 -0.3048)
			(stroke
				(width 0.1)
				(type default)
			)
			(layer "F.Fab")
		)
		(fp_line
			(start 0.12065 -0.2794)
			(end 0.12065 -0.3048)
			(stroke
				(width 0.1)
				(type default)
			)
			(layer "F.Fab")
		)
		(fp_line
			(start 0.67945 -0.3048)
			(end 0.67945 0.3048)
			(stroke
				(width 0.1)
				(type default)
			)
			(layer "F.Fab")
		)
		(fp_line
			(start 0.67945 0.3048)
			(end 0.120396 0.3048)
			(stroke
				(width 0.1)
				(type default)
			)
			(layer "F.Fab")
		)
		(pad "1" smd circle
			(at -0.40005 0)
			(size 0 0)
			(layers "F.Cu" "F.Mask" "F.Paste")
			(net "PVCCIN_CPU0_VCC")
		)
		(pad "2" smd circle
			(at 0.40005 0)
			(size 0 0)
			(layers "F.Cu" "F.Mask" "F.Paste")
			(net "GND")
		)
	)
	(footprint ""
		(layer "F.Cu")
		(at 213.41588 -125.821948)
		(property "Reference" "C1317"
			(at 0 0 0)
			(layer "F.SilkS")
			(hide yes)
			(effects
				(font
					(size 1.27 1.27)
				)
			)
		)
		(property "Value" ""
			(at 0 0 0)
			(layer "F.Fab")
			(effects
				(font
					(size 1.27 1.27)
				)
			)
		)
		(duplicate_pad_numbers_are_jumpers no)
		(fp_line
			(start -0.7874 -0.4064)
			(end 0.7874 -0.4064)
			(stroke
				(width 0.1524)
				(type default)
			)
			(layer "F.SilkS")
		)
		(fp_line
			(start -0.7874 0.4064)
			(end -0.7874 -0.4064)
			(stroke
				(width 0.1524)
				(type default)
			)
			(layer "F.SilkS")
		)
		(fp_line
			(start 0.7874 -0.4064)
			(end 0.7874 0.4064)
			(stroke
				(width 0.1524)
				(type default)
			)
			(layer "F.SilkS")
		)
		(fp_line
			(start 0.7874 0.4064)
			(end -0.7874 0.4064)
			(stroke
				(width 0.1524)
				(type default)
			)
			(layer "F.SilkS")
		)
		(fp_line
			(start -0.67945 -0.305054)
			(end -0.12065 -0.305054)
			(stroke
				(width 0.1)
				(type default)
			)
			(layer "F.Fab")
		)
		(fp_line
			(start -0.67945 0.3048)
			(end -0.67945 -0.305054)
			(stroke
				(width 0.1)
				(type default)
			)
			(layer "F.Fab")
		)
		(fp_line
			(start -0.12065 -0.305054)
			(end -0.12065 -0.2794)
			(stroke
				(width 0.1)
				(type default)
			)
			(layer "F.Fab")
		)
		(fp_line
			(start -0.12065 -0.2794)
			(end 0.12065 -0.2794)
			(stroke
				(width 0.1)
				(type default)
			)
			(layer "F.Fab")
		)
		(fp_line
			(start -0.12065 0.2794)
			(end -0.12065 0.3048)
			(stroke
				(width 0.1)
				(type default)
			)
			(layer "F.Fab")
		)
		(fp_line
			(start -0.12065 0.3048)
			(end -0.67945 0.3048)
			(stroke
				(width 0.1)
				(type default)
			)
			(layer "F.Fab")
		)
		(fp_line
			(start 0.120396 0.2794)
			(end -0.12065 0.2794)
			(stroke
				(width 0.1)
				(type default)
			)
			(layer "F.Fab")
		)
		(fp_line
			(start 0.120396 0.3048)
			(end 0.120396 0.2794)
			(stroke
				(width 0.1)
				(type default)
			)
			(layer "F.Fab")
		)
		(fp_line
			(start 0.12065 -0.3048)
			(end 0.67945 -0.3048)
			(stroke
				(width 0.1)
				(type default)
			)
			(layer "F.Fab")
		)
		(fp_line
			(start 0.12065 -0.2794)
			(end 0.12065 -0.3048)
			(stroke
				(width 0.1)
				(type default)
			)
			(layer "F.Fab")
		)
		(fp_line
			(start 0.67945 -0.3048)
			(end 0.67945 0.3048)
			(stroke
				(width 0.1)
				(type default)
			)
			(layer "F.Fab")
		)
		(fp_line
			(start 0.67945 0.3048)
			(end 0.120396 0.3048)
			(stroke
				(width 0.1)
				(type default)
			)
			(layer "F.Fab")
		)
		(pad "1" smd circle
			(at -0.40005 0)
			(size 0 0)
			(layers "F.Cu" "F.Mask" "F.Paste")
			(net "P3V3_AUX")
		)
		(pad "2" smd circle
			(at 0.40005 0)
			(size 0 0)
			(layers "F.Cu" "F.Mask" "F.Paste")
			(net "GND")
		)
	)
	(footprint ""
		(layer "F.Cu")
		(at 381.229616 -97.604072 -90)
		(property "Reference" "C1290"
			(at 0 0 270)
			(layer "F.SilkS")
			(hide yes)
			(effects
				(font
					(size 1.27 1.27)
				)
			)
		)
		(property "Value" ""
			(at 0 0 270)
			(layer "F.Fab")
			(effects
				(font
					(size 1.27 1.27)
				)
			)
		)
		(duplicate_pad_numbers_are_jumpers no)
		(fp_line
			(start -0.7874 0.4064)
			(end -0.7874 -0.4064)
			(stroke
				(width 0.1524)
				(type default)
			)
			(layer "F.SilkS")
		)
		(fp_line
			(start 0.7874 0.4064)
			(end -0.7874 0.4064)
			(stroke
				(width 0.1524)
				(type default)
			)
			(layer "F.SilkS")
		)
		(fp_line
			(start -0.7874 -0.4064)
			(end 0.7874 -0.4064)
			(stroke
				(width 0.1524)
				(type default)
			)
			(layer "F.SilkS")
		)
		(fp_line
			(start 0.7874 -0.4064)
			(end 0.7874 0.4064)
			(stroke
				(width 0.1524)
				(type default)
			)
			(layer "F.SilkS")
		)
		(fp_line
			(start -0.67945 0.3048)
			(end -0.67945 -0.305054)
			(stroke
				(width 0.1)
				(type default)
			)
			(layer "F.Fab")
		)
		(fp_line
			(start -0.12065 0.3048)
			(end -0.67945 0.3048)
			(stroke
				(width 0.1)
				(type default)
			)
			(layer "F.Fab")
		)
		(fp_line
			(start 0.120396 0.3048)
			(end 0.120396 0.2794)
			(stroke
				(width 0.1)
				(type default)
			)
			(layer "F.Fab")
		)
		(fp_line
			(start 0.67945 0.3048)
			(end 0.120396 0.3048)
			(stroke
				(width 0.1)
				(type default)
			)
			(layer "F.Fab")
		)
		(fp_line
			(start -0.12065 0.2794)
			(end -0.12065 0.3048)
			(stroke
				(width 0.1)
				(type default)
			)
			(layer "F.Fab")
		)
		(fp_line
			(start 0.120396 0.2794)
			(end -0.12065 0.2794)
			(stroke
				(width 0.1)
				(type default)
			)
			(layer "F.Fab")
		)
		(fp_line
			(start -0.12065 -0.2794)
			(end 0.12065 -0.2794)
			(stroke
				(width 0.1)
				(type default)
			)
			(layer "F.Fab")
		)
		(fp_line
			(start 0.12065 -0.2794)
			(end 0.12065 -0.3048)
			(stroke
				(width 0.1)
				(type default)
			)
			(layer "F.Fab")
		)
		(fp_line
			(start 0.12065 -0.3048)
			(end 0.67945 -0.3048)
			(stroke
				(width 0.1)
				(type default)
			)
			(layer "F.Fab")
		)
		(fp_line
			(start 0.67945 -0.3048)
			(end 0.67945 0.3048)
			(stroke
				(width 0.1)
				(type default)
			)
			(layer "F.Fab")
		)
		(fp_line
			(start -0.67945 -0.305054)
			(end -0.12065 -0.305054)
			(stroke
				(width 0.1)
				(type default)
			)
			(layer "F.Fab")
		)
		(fp_line
			(start -0.12065 -0.305054)
			(end -0.12065 -0.2794)
			(stroke
				(width 0.1)
				(type default)
			)
			(layer "F.Fab")
		)
		(pad "1" smd circle
			(at -0.40005 0 270)
			(size 0 0)
			(layers "F.Cu" "F.Mask" "F.Paste")
			(net "P3V3_AUX")
		)
		(pad "2" smd circle
			(at 0.40005 0 270)
			(size 0 0)
			(layers "F.Cu" "F.Mask" "F.Paste")
			(net "GND")
		)
	)
	(footprint ""
		(layer "F.Cu")
		(at 419.60673 -408.517344 -90)
		(property "Reference" "C900"
			(at 0 0 270)
			(layer "F.SilkS")
			(hide yes)
			(effects
				(font
					(size 1.27 1.27)
				)
			)
		)
		(property "Value" ""
			(at 0 0 270)
			(layer "F.Fab")
			(effects
				(font
					(size 1.27 1.27)
				)
			)
		)
		(duplicate_pad_numbers_are_jumpers no)
		(fp_line
			(start -0.299974 0.150114)
			(end -0.299974 -0.150114)
			(stroke
				(width 0.1)
				(type default)
			)
			(layer "F.Fab")
		)
		(fp_line
			(start 0.299974 0.150114)
			(end -0.299974 0.150114)
			(stroke
				(width 0.1)
				(type default)
			)
			(layer "F.Fab")
		)
		(fp_line
			(start -0.299974 -0.150114)
			(end 0.299974 -0.150114)
			(stroke
				(width 0.1)
				(type default)
			)
			(layer "F.Fab")
		)
		(fp_line
			(start 0.299974 -0.150114)
			(end 0.299974 0.150114)
			(stroke
				(width 0.1)
				(type default)
			)
			(layer "F.Fab")
		)
		(pad "1" smd rect
			(at -0.2667 0 270)
			(size 0.3048 0.381)
			(layers "F.Cu" "F.Mask" "F.Paste")
			(net "P5E_CPU0_PE3_TX_C_DN<0>")
		)
		(pad "2" smd rect
			(at 0.2667 0 270)
			(size 0.3048 0.381)
			(layers "F.Cu" "F.Mask" "F.Paste")
			(net "P5E_CPU0_PE3_TX_DN<0>")
		)
	)
	(footprint ""
		(layer "F.Cu")
		(at 17.658842 -105.537762 90)
		(property "Reference" "R4420"
			(at 0 0 90)
			(layer "F.SilkS")
			(hide yes)
			(effects
				(font
					(size 1.27 1.27)
				)
			)
		)
		(property "Value" ""
			(at 0 0 90)
			(layer "F.Fab")
			(effects
				(font
					(size 1.27 1.27)
				)
			)
		)
		(duplicate_pad_numbers_are_jumpers no)
		(fp_line
			(start 0.7874 -0.4064)
			(end 0.7874 0.4064)
			(stroke
				(width 0.1524)
				(type default)
			)
			(layer "F.SilkS")
		)
		(fp_line
			(start -0.026162 -0.4064)
			(end 0.7874 -0.4064)
			(stroke
				(width 0.1524)
				(type default)
			)
			(layer "F.SilkS")
		)
		(fp_line
			(start 0.7874 0.4064)
			(end -0.7874 0.4064)
			(stroke
				(width 0.1524)
				(type default)
			)
			(layer "F.SilkS")
		)
		(fp_line
			(start -0.7874 0.4064)
			(end -0.7874 -0.4064)
			(stroke
				(width 0.1524)
				(type default)
			)
			(layer "F.SilkS")
		)
		(fp_line
			(start -0.12065 -0.305054)
			(end -0.12065 -0.2794)
			(stroke
				(width 0.1)
				(type default)
			)
			(layer "F.Fab")
		)
		(fp_line
			(start -0.67945 -0.305054)
			(end -0.12065 -0.305054)
			(stroke
				(width 0.1)
				(type default)
			)
			(layer "F.Fab")
		)
		(fp_line
			(start 0.67945 -0.3048)
			(end 0.67945 0.3048)
			(stroke
				(width 0.1)
				(type default)
			)
			(layer "F.Fab")
		)
		(fp_line
			(start 0.12065 -0.3048)
			(end 0.67945 -0.3048)
			(stroke
				(width 0.1)
				(type default)
			)
			(layer "F.Fab")
		)
		(fp_line
			(start 0.12065 -0.2794)
			(end 0.12065 -0.3048)
			(stroke
				(width 0.1)
				(type default)
			)
			(layer "F.Fab")
		)
		(fp_line
			(start -0.12065 -0.2794)
			(end 0.12065 -0.2794)
			(stroke
				(width 0.1)
				(type default)
			)
			(layer "F.Fab")
		)
		(fp_line
			(start 0.120396 0.2794)
			(end -0.12065 0.2794)
			(stroke
				(width 0.1)
				(type default)
			)
			(layer "F.Fab")
		)
		(fp_line
			(start -0.12065 0.2794)
			(end -0.12065 0.3048)
			(stroke
				(width 0.1)
				(type default)
			)
			(layer "F.Fab")
		)
		(fp_line
			(start 0.67945 0.3048)
			(end 0.120396 0.3048)
			(stroke
				(width 0.1)
				(type default)
			)
			(layer "F.Fab")
		)
		(fp_line
			(start 0.120396 0.3048)
			(end 0.120396 0.2794)
			(stroke
				(width 0.1)
				(type default)
			)
			(layer "F.Fab")
		)
		(fp_line
			(start -0.12065 0.3048)
			(end -0.67945 0.3048)
			(stroke
				(width 0.1)
				(type default)
			)
			(layer "F.Fab")
		)
		(fp_line
			(start -0.67945 0.3048)
			(end -0.67945 -0.305054)
			(stroke
				(width 0.1)
				(type default)
			)
			(layer "F.Fab")
		)
		(pad "1" smd circle
			(at -0.40005 0 90)
			(size 0 0)
			(layers "F.Cu" "F.Mask" "F.Paste")
			(net "USB2_HOST_BMC_B_DN")
		)
		(pad "2" smd circle
			(at 0.40005 0 90)
			(size 0 0)
			(layers "F.Cu" "F.Mask" "F.Paste")
			(net "GND")
		)
	)
)
